(kicad_pcb
	(version 20221018)
	(generator pcbnew)
	(general
    (thickness 1.62)
  )
	(paper "A4")
	(title_block
    (title "ECP5 - Datacenter Secure Control Module (DC-SCM)")
    (date "2024-07-01")
    (rev "1.2.1")
		(comment 9 "footprints 202-202 of 506")
	)
	(layers
    (0 "F.Cu" signal)
    (1 "In1.Cu" power)
    (2 "In2.Cu" signal)
    (3 "In3.Cu" power)
    (4 "In4.Cu" power)
    (5 "In5.Cu" signal)
    (6 "In6.Cu" power)
    (31 "B.Cu" signal)
    (32 "B.Adhes" user "B.Adhesive")
    (33 "F.Adhes" user "F.Adhesive")
    (34 "B.Paste" user)
    (35 "F.Paste" user)
    (36 "B.SilkS" user "B.Silkscreen")
    (37 "F.SilkS" user "F.Silkscreen")
    (38 "B.Mask" user)
    (39 "F.Mask" user)
    (40 "Dwgs.User" user "User.Drawings")
    (41 "Cmts.User" user "User.Comments")
    (42 "Eco1.User" user "User.Eco1")
    (43 "Eco2.User" user "User.Eco2")
    (44 "Edge.Cuts" user)
    (45 "Margin" user)
    (46 "B.CrtYd" user "B.Courtyard")
    (47 "F.CrtYd" user "F.Courtyard")
    (48 "B.Fab" user)
    (49 "F.Fab" user)
  )
	(footprint "antmicro-footprints:C_0402_1005Metric" (layer "F.Cu")
    (at 135.545 168.325 -90)
    (descr "Capacitor SMD 0402")
    (tags "capacitor SMD 0402")
    (property "Author" "Antmicro")
    (property "Dielectric" "X5R")
    (property "License" "Apache-2.0")
    (property "MPN" "GRM155R61H104KE14D")
    (property "Manufacturer" "Murata")
    (property "Public" "False")
    (property "Sheetfile" "pcie-conn.kicad_sch")
    (property "Sheetname" "PCIe-connector")
    (property "Val" "100n")
    (property "Voltage" "50V")
    (property "ki_description" "SMD Multilayer Ceramic Capacitor, 0.1 µF, 50 V, 0402 [1005 Metric], ± 10%, X5R, GRM Series")
    (property "ki_keywords" "0402, SMT, CAPACITOR, PASSIVE, CERAMIC, MLCC")
    (attr smd)
    (fp_text reference "C34" (at 2.14 -0.01 90) (layer "F.SilkS")
        (effects (font (size 0.7 0.7) (thickness 0.127)))
    )
    (fp_text value "C_100n_0402" (at 0 1.17 90) (layer "F.Fab")
        (effects (font (size 1 1) (thickness 0.15)))
    )
    (fp_text user "License: Apache-2.0" (at -0.939 5.799 -90) (layer "F.Fab") hide
        (effects (font (size 0.7 0.7) (thickness 0.15)) (justify left bottom))
    )
    (fp_text user "Author: Antmicro" (at -0.939 3.399 -90) (layer "F.Fab") hide
        (effects (font (size 0.7 0.7) (thickness 0.15)) (justify left bottom))
    )
    (fp_text user "${REFERENCE}" (at 0 0 90) (layer "F.Fab")
        (effects (font (size 0.25 0.25) (thickness 0.04)))
    )
    (fp_rect (start -0.925 -0.47) (end 0.925 0.47)
      (stroke (width 0.05) (type default)) (fill none) (layer "F.CrtYd"))
    (fp_line (start -0.494 -0.25) (end 0.504 -0.25)
      (stroke (width 0.15) (type solid)) (layer "F.Fab"))
    (fp_line (start -0.494 0.248) (end -0.494 -0.25)
      (stroke (width 0.15) (type solid)) (layer "F.Fab"))
    (fp_line (start 0.504 -0.25) (end 0.504 0.248)
      (stroke (width 0.15) (type solid)) (layer "F.Fab"))
    (fp_line (start 0.504 0.248) (end -0.494 0.248)
      (stroke (width 0.15) (type solid)) (layer "F.Fab"))
    (pad "1" smd roundrect (at -0.48 0 270) (size 0.59 0.64) (layers "F.Cu" "F.Paste" "F.Mask") (roundrect_rratio 0.25)
      (net 212 "Net-(J2-PET3_P)") (pintype "passive"))
    (pad "2" smd roundrect (at 0.48 0 270) (size 0.59 0.64) (layers "F.Cu" "F.Paste" "F.Mask") (roundrect_rratio 0.25)
      (net 691 "PCIE_HPM_TX3_P") (pintype "passive"))
  )
)
